(kicad_pcb
	(version 20241229)
	(generator "pcbnew")
	(generator_version "9.0")
	(general
		(thickness 1.61)
		(legacy_teardrops no)
	)
	(paper "A3")
	(title_block
		(title "SO-DIMM DDR5 Tester")
		(date "2025-11-26")
		(rev "1.3.0")
		(comment 9 "footprints 601-606 of 627")
	)
	(layers
		(0 "F.Cu" signal)
		(4 "In1.Cu" power)
		(6 "In2.Cu" mixed)
		(8 "In3.Cu" power)
		(10 "In4.Cu" mixed)
		(12 "In5.Cu" power)
		(14 "In6.Cu" mixed)
		(16 "In7.Cu" power)
		(18 "In8.Cu" power)
		(20 "In9.Cu" mixed)
		(22 "In10.Cu" power)
		(2 "B.Cu" signal)
		(9 "F.Adhes" user "F.Adhesive")
		(11 "B.Adhes" user "B.Adhesive")
		(13 "F.Paste" user)
		(15 "B.Paste" user)
		(5 "F.SilkS" user "F.Silkscreen")
		(7 "B.SilkS" user "B.Silkscreen")
		(1 "F.Mask" user)
		(3 "B.Mask" user)
		(17 "Dwgs.User" user "User.Drawings")
		(19 "Cmts.User" user "User.Comments")
		(21 "Eco1.User" user "User.Eco1")
		(23 "Eco2.User" user "User.Eco2")
		(25 "Edge.Cuts" user)
		(27 "Margin" user)
		(31 "F.CrtYd" user "F.Courtyard")
		(29 "B.CrtYd" user "B.Courtyard")
		(35 "F.Fab" user)
		(33 "B.Fab" user)
	)
	(footprint "antmicro-footprints:C_0402_1005Metric"
		(layer "B.Cu")
		(at 137.525501 204.850501 -90)
		(descr "Capacitor SMD 0402")
		(tags "capacitor SMD 0402")
		(property "Reference" "C233"
			(at 0 0.699 90)
			(layer "B.SilkS")
			(hide yes)
			(effects
				(font
					(size 0.7 0.7)
					(thickness 0.15)
				)
				(justify left bottom mirror)
			)
		)
		(property "Value" "C_100n_0402"
			(at -1.022927 -2.155213 90)
			(layer "B.Fab")
			(effects
				(font
					(size 0.7 0.7)
					(thickness 0.15)
				)
				(justify left bottom mirror)
			)
		)
		(property "Datasheet" "https://www.murata.com/products/productdetail?partno=GRM155R61H104KE14%23"
			(at 0 0 270)
			(layer "F.Fab")
			(hide yes)
			(effects
				(font
					(size 1.27 1.27)
					(thickness 0.15)
				)
			)
		)
		(property "Author" "Antmicro"
			(at -67.325 342.376002 0)
			(layer "B.Fab")
			(hide yes)
			(effects
				(font
					(size 1 1)
					(thickness 0.15)
				)
				(justify mirror)
			)
		)
		(property "Dielectric" "X5R"
			(at -67.325 342.376002 0)
			(layer "B.Fab")
			(hide yes)
			(effects
				(font
					(size 1 1)
					(thickness 0.15)
				)
				(justify mirror)
			)
		)
		(property "License" "Apache-2.0"
			(at -67.325 342.376002 0)
			(layer "B.Fab")
			(hide yes)
			(effects
				(font
					(size 1 1)
					(thickness 0.15)
				)
				(justify mirror)
			)
		)
		(property "MPN" "GRM155R61H104KE14D"
			(at -67.325 342.376002 0)
			(layer "B.Fab")
			(hide yes)
			(effects
				(font
					(size 1 1)
					(thickness 0.15)
				)
				(justify mirror)
			)
		)
		(property "Manufacturer" "Murata"
			(at -67.325 342.376002 0)
			(layer "B.Fab")
			(hide yes)
			(effects
				(font
					(size 1 1)
					(thickness 0.15)
				)
				(justify mirror)
			)
		)
		(property "Val" "100n"
			(at -67.325 342.376002 0)
			(layer "B.Fab")
			(hide yes)
			(effects
				(font
					(size 1 1)
					(thickness 0.15)
				)
				(justify mirror)
			)
		)
		(property "Voltage" "50V"
			(at -67.325 342.376002 0)
			(layer "B.Fab")
			(hide yes)
			(effects
				(font
					(size 1 1)
					(thickness 0.15)
				)
				(justify mirror)
			)
		)
		(sheetname "/FPGA MGT Interface/")
		(sheetfile "fpga-mgt.kicad_sch")
		(attr smd)
		(fp_rect
			(start -0.9659 0.481258)
			(end 0.9649 -0.458742)
			(stroke
				(width 0.05)
				(type solid)
			)
			(fill no)
			(layer "B.CrtYd")
		)
		(fp_line
			(start -0.499 0.25)
			(end 0.499 0.25)
			(stroke
				(width 0.15)
				(type solid)
			)
			(layer "B.Fab")
		)
		(fp_line
			(start 0.499 0.25)
			(end 0.499 -0.248)
			(stroke
				(width 0.15)
				(type solid)
			)
			(layer "B.Fab")
		)
		(fp_line
			(start -0.499 -0.248)
			(end -0.499 0.25)
			(stroke
				(width 0.15)
				(type solid)
			)
			(layer "B.Fab")
		)
		(fp_line
			(start 0.499 -0.248)
			(end -0.499 -0.248)
			(stroke
				(width 0.15)
				(type solid)
			)
			(layer "B.Fab")
		)
		(pad "1" smd roundrect
			(at -0.484 0 270)
			(size 0.59 0.64)
			(layers "B.Cu" "B.Mask" "B.Paste")
			(roundrect_rratio 0.25)
			(net 30 "/FPGA MGT Interface/GTX_TX2_N")
			(pintype "passive")
		)
		(pad "2" smd roundrect
			(at 0.484 0 270)
			(size 0.59 0.64)
			(layers "B.Cu" "B.Mask" "B.Paste")
			(roundrect_rratio 0.25)
			(net 31 "/FPGA MGT Interface/PCIE.TXD1_N")
			(pintype "passive")
		)
	)
	(footprint "antmicro-footprints:C_0402_1005Metric"
		(layer "B.Cu")
		(at 131.525501 204.850501 90)
		(descr "Capacitor SMD 0402")
		(tags "capacitor SMD 0402")
		(property "Reference" "C229"
			(at 0 0.699 270)
			(layer "B.SilkS")
			(hide yes)
			(effects
				(font
					(size 0.7 0.7)
					(thickness 0.15)
				)
				(justify left bottom mirror)
			)
		)
		(property "Value" "C_100n_0402"
			(at -1.022927 -2.155213 270)
			(layer "B.Fab")
			(effects
				(font
					(size 0.7 0.7)
					(thickness 0.15)
				)
				(justify left bottom mirror)
			)
		)
		(property "Datasheet" "https://www.murata.com/products/productdetail?partno=GRM155R61H104KE14%23"
			(at 0 0 90)
			(layer "F.Fab")
			(hide yes)
			(effects
				(font
					(size 1.27 1.27)
					(thickness 0.15)
				)
			)
		)
		(property "Author" "Antmicro"
			(at 336.376002 73.325 0)
			(layer "B.Fab")
			(hide yes)
			(effects
				(font
					(size 1 1)
					(thickness 0.15)
				)
				(justify mirror)
			)
		)
		(property "Dielectric" "X5R"
			(at 336.376002 73.325 0)
			(layer "B.Fab")
			(hide yes)
			(effects
				(font
					(size 1 1)
					(thickness 0.15)
				)
				(justify mirror)
			)
		)
		(property "License" "Apache-2.0"
			(at 336.376002 73.325 0)
			(layer "B.Fab")
			(hide yes)
			(effects
				(font
					(size 1 1)
					(thickness 0.15)
				)
				(justify mirror)
			)
		)
		(property "MPN" "GRM155R61H104KE14D"
			(at 336.376002 73.325 0)
			(layer "B.Fab")
			(hide yes)
			(effects
				(font
					(size 1 1)
					(thickness 0.15)
				)
				(justify mirror)
			)
		)
		(property "Manufacturer" "Murata"
			(at 336.376002 73.325 0)
			(layer "B.Fab")
			(hide yes)
			(effects
				(font
					(size 1 1)
					(thickness 0.15)
				)
				(justify mirror)
			)
		)
		(property "Val" "100n"
			(at 336.376002 73.325 0)
			(layer "B.Fab")
			(hide yes)
			(effects
				(font
					(size 1 1)
					(thickness 0.15)
				)
				(justify mirror)
			)
		)
		(property "Voltage" "50V"
			(at 336.376002 73.325 0)
			(layer "B.Fab")
			(hide yes)
			(effects
				(font
					(size 1 1)
					(thickness 0.15)
				)
				(justify mirror)
			)
		)
		(sheetname "/FPGA MGT Interface/")
		(sheetfile "fpga-mgt.kicad_sch")
		(attr smd)
		(fp_rect
			(start -0.9659 0.481258)
			(end 0.9649 -0.458742)
			(stroke
				(width 0.05)
				(type solid)
			)
			(fill no)
			(layer "B.CrtYd")
		)
		(fp_line
			(start 0.499 -0.248)
			(end -0.499 -0.248)
			(stroke
				(width 0.15)
				(type solid)
			)
			(layer "B.Fab")
		)
		(fp_line
			(start -0.499 -0.248)
			(end -0.499 0.25)
			(stroke
				(width 0.15)
				(type solid)
			)
			(layer "B.Fab")
		)
		(fp_line
			(start 0.499 0.25)
			(end 0.499 -0.248)
			(stroke
				(width 0.15)
				(type solid)
			)
			(layer "B.Fab")
		)
		(fp_line
			(start -0.499 0.25)
			(end 0.499 0.25)
			(stroke
				(width 0.15)
				(type solid)
			)
			(layer "B.Fab")
		)
		(pad "1" smd roundrect
			(at -0.484 0 90)
			(size 0.59 0.64)
			(layers "B.Cu" "B.Mask" "B.Paste")
			(roundrect_rratio 0.25)
			(net 22 "/FPGA MGT Interface/PCIE.TXD0_P")
			(pintype "passive")
		)
		(pad "2" smd roundrect
			(at 0.484 0 90)
			(size 0.59 0.64)
			(layers "B.Cu" "B.Mask" "B.Paste")
			(roundrect_rratio 0.25)
			(net 23 "/FPGA MGT Interface/GTX_TX3_P")
			(pintype "passive")
		)
	)
	(footprint "antmicro-footprints:C_0402_1005Metric"
		(layer "B.Cu")
		(at 142.875501 167.301 180)
		(descr "Capacitor SMD 0402 (1005 Metric), square (rectangular) end terminal, IPC_7351 nominal, (Body size source: IPC-SM-782 page 76, https://www.pcb-3d.com/wordpress/wp-content/uploads/ipc-sm-782a_amendment_1_and_2.pdf)")
		(tags "capacitor 0402")
		(property "Reference" "C74"
			(at 0 1.17 0)
			(layer "B.SilkS")
			(hide yes)
			(effects
				(font
					(size 0.7 0.7)
					(thickness 0.15)
				)
				(justify left bottom mirror)
			)
		)
		(property "Value" "C_100n_0402"
			(at 0 -1.169 0)
			(layer "B.Fab")
			(effects
				(font
					(size 0.7 0.7)
					(thickness 0.15)
				)
				(justify left bottom mirror)
			)
		)
		(property "Datasheet" "https://www.murata.com/products/productdetail?partno=GRM155R61H104KE14%23"
			(at 0 0 180)
			(layer "F.Fab")
			(hide yes)
			(effects
				(font
					(size 1.27 1.27)
					(thickness 0.15)
				)
			)
		)
		(property "Author" "Antmicro"
			(at 285.751002 334.602 0)
			(layer "B.Fab")
			(hide yes)
			(effects
				(font
					(size 1 1)
					(thickness 0.15)
				)
				(justify mirror)
			)
		)
		(property "Dielectric" "X5R"
			(at 285.751002 334.602 0)
			(layer "B.Fab")
			(hide yes)
			(effects
				(font
					(size 1 1)
					(thickness 0.15)
				)
				(justify mirror)
			)
		)
		(property "License" "Apache-2.0"
			(at 285.751002 334.602 0)
			(layer "B.Fab")
			(hide yes)
			(effects
				(font
					(size 1 1)
					(thickness 0.15)
				)
				(justify mirror)
			)
		)
		(property "MPN" "GRM155R61H104KE14D"
			(at 285.751002 334.602 0)
			(layer "B.Fab")
			(hide yes)
			(effects
				(font
					(size 1 1)
					(thickness 0.15)
				)
				(justify mirror)
			)
		)
		(property "Manufacturer" "Murata"
			(at 285.751002 334.602 0)
			(layer "B.Fab")
			(hide yes)
			(effects
				(font
					(size 1 1)
					(thickness 0.15)
				)
				(justify mirror)
			)
		)
		(property "Val" "100n"
			(at 285.751002 334.602 0)
			(layer "B.Fab")
			(hide yes)
			(effects
				(font
					(size 1 1)
					(thickness 0.15)
				)
				(justify mirror)
			)
		)
		(property "Voltage" "50V"
			(at 285.751002 334.602 0)
			(layer "B.Fab")
			(hide yes)
			(effects
				(font
					(size 1 1)
					(thickness 0.15)
				)
				(justify mirror)
			)
		)
		(sheetname "/FPGA power/")
		(sheetfile "fpga-power.kicad_sch")
		(attr smd)
		(fp_rect
			(start -0.9656 0.4572)
			(end 0.9652 -0.4828)
			(stroke
				(width 0.05)
				(type solid)
			)
			(fill no)
			(layer "B.CrtYd")
		)
		(fp_line
			(start 0.498 0.25)
			(end 0.498 -0.248)
			(stroke
				(width 0.15)
				(type solid)
			)
			(layer "B.Fab")
		)
		(fp_line
			(start 0.498 -0.248)
			(end -0.5 -0.248)
			(stroke
				(width 0.15)
				(type solid)
			)
			(layer "B.Fab")
		)
		(fp_line
			(start -0.5 0.25)
			(end 0.498 0.25)
			(stroke
				(width 0.15)
				(type solid)
			)
			(layer "B.Fab")
		)
		(fp_line
			(start -0.5 -0.248)
			(end -0.5 0.25)
			(stroke
				(width 0.15)
				(type solid)
			)
			(layer "B.Fab")
		)
		(pad "1" smd roundrect
			(at -0.5 0 90)
			(size 0.6 0.6)
			(layers "B.Cu" "B.Mask" "B.Paste")
			(roundrect_rratio 0.25)
			(net 1 "GND")
			(pintype "passive")
		)
		(pad "2" smd roundrect
			(at 0.498 0 180)
			(size 0.6 0.6)
			(layers "B.Cu" "B.Mask" "B.Paste")
			(roundrect_rratio 0.25)
			(net 206 "+1V1")
			(pintype "passive")
		)
	)
	(footprint "antmicro-footprints:C_0402_1005Metric"
		(layer "B.Cu")
		(at 137.875001 178.3025)
		(descr "Capacitor SMD 0402 (1005 Metric), square (rectangular) end terminal, IPC_7351 nominal, (Body size source: IPC-SM-782 page 76, https://www.pcb-3d.com/wordpress/wp-content/uploads/ipc-sm-782a_amendment_1_and_2.pdf)")
		(tags "capacitor 0402")
		(property "Reference" "C67"
			(at 0 1.17 180)
			(layer "B.SilkS")
			(hide yes)
			(effects
				(font
					(size 0.7 0.7)
					(thickness 0.15)
				)
				(justify left bottom mirror)
			)
		)
		(property "Value" "C_4u7_0402"
			(at 0 -1.169 180)
			(layer "B.Fab")
			(effects
				(font
					(size 0.7 0.7)
					(thickness 0.15)
				)
				(justify left bottom mirror)
			)
		)
		(property "Datasheet" "https://www.murata.com/products/productdetail?partno=GRM155R61A475MEAA%23"
			(at 0 0 0)
			(layer "F.Fab")
			(hide yes)
			(effects
				(font
					(size 1.27 1.27)
					(thickness 0.15)
				)
			)
		)
		(property "Author" "Antmicro"
			(at 0 0 0)
			(layer "B.Fab")
			(hide yes)
			(effects
				(font
					(size 1 1)
					(thickness 0.15)
				)
				(justify mirror)
			)
		)
		(property "Dielectric" ""
			(at 0 0 0)
			(layer "B.Fab")
			(hide yes)
			(effects
				(font
					(size 1 1)
					(thickness 0.15)
				)
				(justify mirror)
			)
		)
		(property "License" "Apache-2.0"
			(at 0 0 0)
			(layer "B.Fab")
			(hide yes)
			(effects
				(font
					(size 1 1)
					(thickness 0.15)
				)
				(justify mirror)
			)
		)
		(property "MPN" "GRM155R61A475MEAAD"
			(at 0 0 0)
			(layer "B.Fab")
			(hide yes)
			(effects
				(font
					(size 1 1)
					(thickness 0.15)
				)
				(justify mirror)
			)
		)
		(property "Manufacturer" "Murata"
			(at 0 0 0)
			(layer "B.Fab")
			(hide yes)
			(effects
				(font
					(size 1 1)
					(thickness 0.15)
				)
				(justify mirror)
			)
		)
		(property "Val" "4u7"
			(at 0 0 0)
			(layer "B.Fab")
			(hide yes)
			(effects
				(font
					(size 1 1)
					(thickness 0.15)
				)
				(justify mirror)
			)
		)
		(property "Voltage" ""
			(at 0 0 0)
			(layer "B.Fab")
			(hide yes)
			(effects
				(font
					(size 1 1)
					(thickness 0.15)
				)
				(justify mirror)
			)
		)
		(sheetname "/FPGA power/")
		(sheetfile "fpga-power.kicad_sch")
		(attr smd)
		(fp_rect
			(start -0.9656 0.4572)
			(end 0.9652 -0.4828)
			(stroke
				(width 0.05)
				(type solid)
			)
			(fill no)
			(layer "B.CrtYd")
		)
		(fp_line
			(start -0.5 -0.248)
			(end -0.5 0.25)
			(stroke
				(width 0.15)
				(type solid)
			)
			(layer "B.Fab")
		)
		(fp_line
			(start -0.5 0.25)
			(end 0.498 0.25)
			(stroke
				(width 0.15)
				(type solid)
			)
			(layer "B.Fab")
		)
		(fp_line
			(start 0.498 -0.248)
			(end -0.5 -0.248)
			(stroke
				(width 0.15)
				(type solid)
			)
			(layer "B.Fab")
		)
		(fp_line
			(start 0.498 0.25)
			(end 0.498 -0.248)
			(stroke
				(width 0.15)
				(type solid)
			)
			(layer "B.Fab")
		)
		(pad "1" smd roundrect
			(at -0.5 0 270)
			(size 0.6 0.6)
			(layers "B.Cu" "B.Mask" "B.Paste")
			(roundrect_rratio 0.25)
			(net 227 "+1V0")
			(pintype "passive")
		)
		(pad "2" smd roundrect
			(at 0.498 0)
			(size 0.6 0.6)
			(layers "B.Cu" "B.Mask" "B.Paste")
			(roundrect_rratio 0.25)
			(net 1 "GND")
			(pintype "passive")
		)
	)
	(footprint "antmicro-footprints:C_0402_1005Metric"
		(layer "B.Cu")
		(at 84.289 129.7)
		(descr "Capacitor SMD 0402")
		(tags "capacitor SMD 0402")
		(property "Reference" "C234"
			(at 0 0.699 180)
			(layer "B.SilkS")
			(hide yes)
			(effects
				(font
					(size 0.7 0.7)
					(thickness 0.15)
				)
				(justify left bottom mirror)
			)
		)
		(property "Value" "C_100n_0402"
			(at -1.022927 -2.155213 180)
			(layer "B.Fab")
			(effects
				(font
					(size 0.7 0.7)
					(thickness 0.15)
				)
				(justify left bottom mirror)
			)
		)
		(property "Datasheet" "https://www.murata.com/products/productdetail?partno=GRM155R61H104KE14%23"
			(at 0 0 0)
			(layer "F.Fab")
			(hide yes)
			(effects
				(font
					(size 1.27 1.27)
					(thickness 0.15)
				)
			)
		)
		(property "Author" "Antmicro"
			(at 0 0 0)
			(layer "B.Fab")
			(hide yes)
			(effects
				(font
					(size 1 1)
					(thickness 0.15)
				)
				(justify mirror)
			)
		)
		(property "Dielectric" "X5R"
			(at 0 0 0)
			(layer "B.Fab")
			(hide yes)
			(effects
				(font
					(size 1 1)
					(thickness 0.15)
				)
				(justify mirror)
			)
		)
		(property "License" "Apache-2.0"
			(at 0 0 0)
			(layer "B.Fab")
			(hide yes)
			(effects
				(font
					(size 1 1)
					(thickness 0.15)
				)
				(justify mirror)
			)
		)
		(property "MPN" "GRM155R61H104KE14D"
			(at 0 0 0)
			(layer "B.Fab")
			(hide yes)
			(effects
				(font
					(size 1 1)
					(thickness 0.15)
				)
				(justify mirror)
			)
		)
		(property "Manufacturer" "Murata"
			(at 0 0 0)
			(layer "B.Fab")
			(hide yes)
			(effects
				(font
					(size 1 1)
					(thickness 0.15)
				)
				(justify mirror)
			)
		)
		(property "Val" "100n"
			(at 0 0 0)
			(layer "B.Fab")
			(hide yes)
			(effects
				(font
					(size 1 1)
					(thickness 0.15)
				)
				(justify mirror)
			)
		)
		(property "Voltage" "50V"
			(at 0 0 0)
			(layer "B.Fab")
			(hide yes)
			(effects
				(font
					(size 1 1)
					(thickness 0.15)
				)
				(justify mirror)
			)
		)
		(sheetname "/Ethernet/")
		(sheetfile "ethernet.kicad_sch")
		(attr smd)
		(fp_rect
			(start -0.9659 0.481258)
			(end 0.9649 -0.458742)
			(stroke
				(width 0.05)
				(type solid)
			)
			(fill no)
			(layer "B.CrtYd")
		)
		(fp_line
			(start -0.499 -0.248)
			(end -0.499 0.25)
			(stroke
				(width 0.15)
				(type solid)
			)
			(layer "B.Fab")
		)
		(fp_line
			(start -0.499 0.25)
			(end 0.499 0.25)
			(stroke
				(width 0.15)
				(type solid)
			)
			(layer "B.Fab")
		)
		(fp_line
			(start 0.499 -0.248)
			(end -0.499 -0.248)
			(stroke
				(width 0.15)
				(type solid)
			)
			(layer "B.Fab")
		)
		(fp_line
			(start 0.499 0.25)
			(end 0.499 -0.248)
			(stroke
				(width 0.15)
				(type solid)
			)
			(layer "B.Fab")
		)
		(pad "1" smd roundrect
			(at -0.484 0)
			(size 0.59 0.64)
			(layers "B.Cu" "B.Mask" "B.Paste")
			(roundrect_rratio 0.25)
			(net 32 "Net-(C234-Pad1)")
			(pintype "passive")
		)
		(pad "2" smd roundrect
			(at 0.484 0)
			(size 0.59 0.64)
			(layers "B.Cu" "B.Mask" "B.Paste")
			(roundrect_rratio 0.25)
			(net 1 "GND")
			(pintype "passive")
		)
	)
	(footprint "antmicro-footprints:TP_SMD_1mm"
		(layer "B.Cu")
		(at 173.9 189.5 180)
		(property "Reference" "TP69"
			(at 0.5 0.05 0)
			(layer "B.SilkS")
			(effects
				(font
					(size 0.7 0.7)
					(thickness 0.15)
				)
				(justify left bottom mirror)
			)
		)
		(property "Value" "TP_1mm_SMD"
			(at 0 -1.4 0)
			(layer "B.Fab")
			(effects
				(font
					(size 0.7 0.7)
					(thickness 0.15)
				)
				(justify left bottom mirror)
			)
		)
		(property "MPN" ""
			(at 0 0 0)
			(unlocked yes)
			(layer "B.Fab")
			(hide yes)
			(effects
				(font
					(size 1 1)
					(thickness 0.15)
				)
				(justify mirror)
			)
		)
		(property "Manufacturer" ""
			(at 0 0 0)
			(unlocked yes)
			(layer "B.Fab")
			(hide yes)
			(effects
				(font
					(size 1 1)
					(thickness 0.15)
				)
				(justify mirror)
			)
		)
		(property "Author" "Antmicro"
			(at 0 0 0)
			(unlocked yes)
			(layer "B.Fab")
			(hide yes)
			(effects
				(font
					(size 1 1)
					(thickness 0.15)
				)
				(justify mirror)
			)
		)
		(property "License" "Apache-2.0"
			(at 0 0 0)
			(unlocked yes)
			(layer "B.Fab")
			(hide yes)
			(effects
				(font
					(size 1 1)
					(thickness 0.15)
				)
				(justify mirror)
			)
		)
		(sheetname "/I^{2}C/")
		(sheetfile "i2c.kicad_sch")
		(attr exclude_from_pos_files)
		(fp_circle
			(center 0 0)
			(end 0.6 0)
			(stroke
				(width 0.05)
				(type default)
			)
			(fill no)
			(layer "B.CrtYd")
		)
		(fp_text user "Author: Antmicro"
			(at -0.5 -4 0)
			(layer "B.Fab")
			(effects
				(font
					(size 0.7 0.7)
					(thickness 0.15)
				)
				(justify left bottom mirror)
			)
		)
		(fp_text user "${REFERENCE}"
			(at -0.5 -2.8 0)
			(layer "B.Fab")
			(effects
				(font
					(size 0.7 0.7)
					(thickness 0.15)
				)
				(justify left bottom mirror)
			)
		)
		(fp_text user "License: Apache-2.0"
			(at -0.5 -5.2 0)
			(layer "B.Fab")
			(effects
				(font
					(size 0.7 0.7)
					(thickness 0.15)
				)
				(justify left bottom mirror)
			)
		)
		(pad "1" smd circle
			(at 0 0 180)
			(size 1 1)
			(layers "B.Cu" "B.Mask")
			(net 761 "Net-(U34-SDA)")
			(pinfunction "1")
			(pintype "passive")
		)
	)
)
